FILE_TYPE = CONNECTIVITY;
{Allegro Design Entry HDL 16.6-p007 (v16-6-112F) 10/10/2012}
"PAGE_NUMBER" = 75;
0"NC";
1"GND\g";
2"GND\g";
3"GND\g";
4"GND\g";
5"GND\g";
6"GND\g";
7"GND\g";
8"GND\g";
%"GND"
"1","(-5675,400)","0","mstr_symbols","I10";
;
HDL_POWER"GND"
BODY_TYPE"PLUMBING"
SIZE"1B"
CDS_LIB"mstr_symbols"
VOLTAGE"0.0V";
"A\NAC"1;
%"GND"
"1","(-3775,400)","0","mstr_symbols","I11";
;
HDL_POWER"GND"
BODY_TYPE"PLUMBING"
CDS_LIB"mstr_symbols"
SIZE"1B"
VOLTAGE"0.0V";
"A\NAC"2;
%"GND"
"1","(-1975,400)","0","mstr_symbols","I12";
;
HDL_POWER"GND"
BODY_TYPE"PLUMBING"
CDS_LIB"mstr_symbols"
SIZE"1B"
VOLTAGE"0.0V";
"A\NAC"3;
%"GND"
"1","(-2275,400)","0","mstr_symbols","I13";
;
HDL_POWER"GND"
BODY_TYPE"PLUMBING"
SIZE"1B"
CDS_LIB"mstr_symbols"
VOLTAGE"0.0V";
"A\NAC"4;
%"GND"
"1","(-4150,400)","0","mstr_symbols","I14";
;
HDL_POWER"GND"
BODY_TYPE"PLUMBING"
SIZE"1B"
CDS_LIB"mstr_symbols"
VOLTAGE"0.0V";
"A\NAC"5;
%"GND"
"1","(-5950,400)","0","mstr_symbols","I15";
;
HDL_POWER"GND"
BODY_TYPE"PLUMBING"
SIZE"1B"
CDS_LIB"mstr_symbols"
VOLTAGE"0.0V";
"A\NAC"6;
%"GND"
"1","(-450,1700)","0","mstr_symbols","I16";
;
HDL_POWER"GND"
BODY_TYPE"PLUMBING"
SIZE"1B"
CDS_LIB"mstr_symbols"
VOLTAGE"0.0V";
"A\NAC"7;
%"SKX_EXT_B"
"27","(-6725,2525)","0","chpset_lib","I17";
;
CDS_SEC"27"
CDS_LOCATION"U2D1"
SEC"27"
CDS_LIB"chpset_lib"
SEC_TYPE"BGA1"
PACK_TYPE"BGA1"
MATERIAL"IC"
PART_NUMBER"TBD"
LOCATION"U2D1";
"VSS<454>"
$PN"P49"6;
"VSS<455>"
$PN"CJ12"6;
"VSS<456>"
$PN"CJ10"6;
"VSS<457>"
$PN"CJ8"6;
"VSS<458>"
$PN"CJ6"6;
"VSS<459>"
$PN"CJ2"6;
"VSS<460>"
$PN"CH83"6;
"VSS<461>"
$PN"CH81"6;
"VSS<462>"
$PN"CH79"6;
"VSS<463>"
$PN"CH73"6;
"VSS<464>"
$PN"CH67"6;
"VSS<465>"
$PN"CH63"6;
"VSS<466>"
$PN"CH19"6;
"VSS<467>"
$PN"CH15"6;
"VSS<468>"
$PN"CH3"6;
"VSS<469>"
$PN"CH1"6;
"VSS<470>"
$PN"CG80"6;
"VSS<471>"
$PN"CG72"6;
"VSS<472>"
$PN"CG68"6;
"VSS<473>"
$PN"CG62"6;
"VSS<474>"
$PN"CG22"6;
"VSS<475>"
$PN"CG18"6;
"VSS<476>"
$PN"P51"6;
"VSS<477>"
$PN"CF83"6;
"VSS<478>"
$PN"CF77"6;
"VSS<479>"
$PN"CF71"6;
"VSS<480>"
$PN"CF69"6;
"VSS<481>"
$PN"CF63"6;
"VSS<482>"
$PN"CF9"6;
"VSS<483>"
$PN"P53"6;
"VSS<484>"
$PN"CE82"6;
"VSS<485>"
$PN"CE70"6;
"VSS<486>"
$PN"CE62"6;
"VSS<487>"
$PN"CE26"6;
"VSS<488>"
$PN"CE20"6;
"VSS<489>"
$PN"CE14"6;
"VSS<490>"
$PN"CE10"6;
"VSS<491>"
$PN"CD81"6;
"VSS<492>"
$PN"CD79"6;
"VSS<493>"
$PN"CD77"6;
"VSS<494>"
$PN"CD75"6;
"VSS<495>"
$PN"CD73"6;
"VSS<496>"
$PN"CD63"6;
"VSS<497>"
$PN"CD13"6;
"VSS<498>"
$PN"CD5"6;
"VSS<499>"
$PN"CC82"6;
"VSS<500>"
$PN"CC80"6;
"VSS<501>"
$PN"CC78"6;
"VSS<502>"
$PN"CC76"6;
"VSS<503>"
$PN"CC74"6;
"VSS<504>"
$PN"CC72"6;
"VSS<505>"
$PN"CC64"6;
"VSS<506>"
$PN"CC24"6;
"VSS<507>"
$PN"CC18"6;
"VSS<508>"
$PN"CC16"6;
"VSS<509>"
$PN"CC4"6;
"VSS<510>"
$PN"CB71"6;
"VSS<511>"
$PN"CB63"6;
"VSS<512>"
$PN"CB27"6;
"VSS<513>"
$PN"CB9"6;
"VSS<514>"
$PN"CB7"6;
"VSS<515>"
$PN"CA70"6;
"VSS<516>"
$PN"CA68"6;
"VSS<517>"
$PN"CA66"6;
"VSS<518>"
$PN"CA64"6;
"VSS<519>"
$PN"CA26"6;
"VSS<520>"
$PN"CA18"6;
"VSS<521>"
$PN"CA14"6;
"VSS<522>"
$PN"CA10"6;
"VSS<523>"
$PN"CA8"6;
"VSS<524>"
$PN"CA6"6;
"VSS<525>"
$PN"CA2"6;
"VSS<526>"
$PN"BY71"6;
"VSS<527>"
$PN"BY69"6;
"VSS<528>"
$PN"BY67"6;
"VSS<529>"
$PN"BY65"6;
"VSS<530>"
$PN"BY63"6;
"VSS<531>"
$PN"BY23"6;
"VSS<532>"
$PN"BY13"6;
"VSS<533>"
$PN"BY11"6;
"VSS<534>"
$PN"BW82"8;
"VSS<535>"
$PN"BW80"8;
"VSS<536>"
$PN"BW78"8;
"VSS<537>"
$PN"BW76"8;
"VSS<538>"
$PN"BW74"8;
"VSS<539>"
$PN"BW72"8;
"VSS<540>"
$PN"BW26"8;
"VSS<541>"
$PN"BW18"8;
"VSS<542>"
$PN"BW16"8;
"VSS<543>"
$PN"BW14"8;
"VSS<544>"
$PN"BW12"8;
"VSS<545>"
$PN"P55"8;
"VSS<546>"
$PN"BW6"8;
"VSS<547>"
$PN"BV25"8;
"VSS<548>"
$PN"BV17"8;
"VSS<549>"
$PN"BU10"8;
"VSS<550>"
$PN"BV5"8;
"VSS<551>"
$PN"BU8"8;
"VSS<552>"
$PN"BT25"8;
"VSS<553>"
$PN"BT23"8;
"VSS<554>"
$PN"BT21"8;
"VSS<555>"
$PN"BT5"8;
"VSS<556>"
$PN"BT3"8;
"VSS<557>"
$PN"BR82"8;
"VSS<558>"
$PN"BR80"8;
"VSS<559>"
$PN"BR78"8;
"VSS<560>"
$PN"BR76"8;
"VSS<561>"
$PN"BR74"8;
"VSS<562>"
$PN"BR72"8;
"VSS<563>"
$PN"BR70"8;
"VSS<564>"
$PN"BR68"8;
"VSS<565>"
$PN"BR66"8;
"VSS<566>"
$PN"BR64"8;
"VSS<567>"
$PN"P57"8;
"VSS<568>"
$PN"BR16"8;
"VSS<569>"
$PN"BR10"8;
"VSS<570>"
$PN"BR6"8;
"VSS<571>"
$PN"BP27"8;
"VSS<572>"
$PN"BP3"8;
"VSS<573>"
$PN"BN26"8;
"VSS<574>"
$PN"BN20"8;
"VSS<575>"
$PN"BN10"8;
"VSS<576>"
$PN"BN6"8;
"VSS<577>"
$PN"BM25"8;
"VSS<578>"
$PN"P59"8;
"VSS<579>"
$PN"BM15"8;
"VSS<580>"
$PN"BM13"8;
"VSS<581>"
$PN"BM9"8;
"VSS<582>"
$PN"BL82"8;
"VSS<583>"
$PN"BL80"8;
"VSS<584>"
$PN"BL78"8;
"VSS<585>"
$PN"BL76"8;
"VSS<586>"
$PN"BL74"8;
"VSS<587>"
$PN"BL72"8;
"VSS<588>"
$PN"BL70"8;
"VSS<589>"
$PN"BL68"8;
"VSS<590>"
$PN"BL66"8;
"VSS<591>"
$PN"BL64"8;
"VSS<592>"
$PN"BL24"8;
"VSS<593>"
$PN"BL22"8;
"VSS<594>"
$PN"P61"8;
"VSS<595>"
$PN"BL12"8;
"VSS<596>"
$PN"BL10"8;
"VSS<597>"
$PN"BL6"8;
"VSS<598>"
$PN"BK19"8;
"VSS<599>"
$PN"BK11"8;
"VSS<600>"
$PN"BK7"8;
"VSS<601>"
$PN"BK3"8;
"VSS<602>"
$PN"BJ6"8;
"VSS<603>"
$PN"BJ4"8;
"VSS<604>"
$PN"BH21"8;
"VSS<605>"
$PN"BH15"8;
"VSS<606>"
$PN"BH11"8;
"VSS<607>"
$PN"BH9"8;
"VSS<608>"
$PN"BH7"8;
"VSS<609>"
$PN"BG82"8;
"VSS<610>"
$PN"BG80"8;
"VSS<611>"
$PN"BG78"8;
"VSS<612>"
$PN"BG76"8;
"VSS<613>"
$PN"BG74"8;
%"SKX_EXT_B"
"28","(-4925,2525)","0","chpset_lib","I18";
;
CDS_SEC"28"
CDS_LOCATION"U2D1"
SEC"28"
CDS_LIB"chpset_lib"
SEC_TYPE"BGA1"
PACK_TYPE"BGA1"
MATERIAL"IC"
PART_NUMBER"TBD"
LOCATION"U2D1";
"VSS<294>"
$PN"DA46"5;
"VSS<295>"
$PN"DA44"5;
"VSS<296>"
$PN"DA38"5;
"VSS<297>"
$PN"DA36"5;
"VSS<298>"
$PN"DA34"5;
"VSS<299>"
$PN"DA32"5;
"VSS<300>"
$PN"DA30"5;
"VSS<301>"
$PN"DA28"5;
"VSS<302>"
$PN"DA26"5;
"VSS<303>"
$PN"DA18"5;
"VSS<304>"
$PN"H53"5;
"VSS<305>"
$PN"DA6"5;
"VSS<306>"
$PN"CY85"5;
"VSS<307>"
$PN"CY83"5;
"VSS<308>"
$PN"CY77"5;
"VSS<309>"
$PN"CY75"5;
"VSS<310>"
$PN"CY69"5;
"VSS<311>"
$PN"CY65"5;
"VSS<312>"
$PN"CY61"5;
"VSS<313>"
$PN"CY59"5;
"VSS<314>"
$PN"CY51"5;
"VSS<315>"
$PN"CY45"5;
"VSS<316>"
$PN"CY41"5;
"VSS<317>"
$PN"CY21"5;
"VSS<318>"
$PN"CY15"5;
"VSS<319>"
$PN"CY13"5;
"VSS<320>"
$PN"CY9"5;
"VSS<321>"
$PN"CY1"5;
"VSS<322>"
$PN"CW82"5;
"VSS<323>"
$PN"CW78"5;
"VSS<324>"
$PN"CW74"5;
"VSS<325>"
$PN"CW68"5;
"VSS<326>"
$PN"CW66"5;
"VSS<327>"
$PN"CW64"5;
"VSS<328>"
$PN"CW54"5;
"VSS<329>"
$PN"CW52"5;
"VSS<330>"
$PN"CW42"5;
"VSS<331>"
$PN"CW40"5;
"VSS<332>"
$PN"CW38"5;
"VSS<333>"
$PN"CW32"5;
"VSS<334>"
$PN"CW26"5;
"VSS<335>"
$PN"CW12"5;
"VSS<336>"
$PN"CV83"5;
"VSS<337>"
$PN"CV81"5;
"VSS<338>"
$PN"CV79"5;
"VSS<339>"
$PN"CV73"5;
"VSS<340>"
$PN"CV67"5;
"VSS<341>"
$PN"CV63"5;
"VSS<342>"
$PN"CV55"5;
"VSS<343>"
$PN"CV53"5;
"VSS<344>"
$PN"CV41"5;
"VSS<345>"
$PN"CV39"5;
"VSS<346>"
$PN"CV37"5;
"VSS<347>"
$PN"CV33"5;
"VSS<348>"
$PN"CV31"5;
"VSS<349>"
$PN"CV27"5;
"VSS<350>"
$PN"CV25"5;
"VSS<351>"
$PN"CV17"5;
"VSS<352>"
$PN"H55"5;
"VSS<353>"
$PN"CV1"5;
"VSS<354>"
$PN"CU86"5;
"VSS<355>"
$PN"CU82"5;
"VSS<356>"
$PN"CU80"5;
"VSS<357>"
$PN"CU78"5;
"VSS<358>"
$PN"CU76"5;
"VSS<359>"
$PN"CU68"5;
"VSS<360>"
$PN"CU62"5;
"VSS<361>"
$PN"CU56"5;
"VSS<362>"
$PN"CU36"5;
"VSS<363>"
$PN"CU34"5;
"VSS<364>"
$PN"CU30"5;
"VSS<365>"
$PN"CU28"5;
"VSS<366>"
$PN"CU22"5;
"VSS<367>"
$PN"CU4"5;
"VSS<368>"
$PN"CT85"5;
"VSS<369>"
$PN"CT83"5;
"VSS<370>"
$PN"CT79"5;
"VSS<371>"
$PN"CT73"5;
"VSS<372>"
$PN"CT57"5;
"VSS<373>"
$PN"CT35"5;
"VSS<374>"
$PN"CT33"1;
"VSS<375>"
$PN"CT29"1;
"VSS<376>"
$PN"CT27"1;
"VSS<377>"
$PN"CT19"1;
"VSS<378>"
$PN"CT13"1;
"VSS<379>"
$PN"H57"1;
"VSS<380>"
$PN"CR86"1;
"VSS<381>"
$PN"CR78"1;
"VSS<382>"
$PN"CR68"1;
"VSS<383>"
$PN"CR66"1;
"VSS<384>"
$PN"CR64"1;
"VSS<385>"
$PN"CR62"1;
"VSS<386>"
$PN"CR58"1;
"VSS<387>"
$PN"CR32"1;
"VSS<388>"
$PN"CR24"1;
"VSS<389>"
$PN"CR22"1;
"VSS<390>"
$PN"CR10"1;
"VSS<391>"
$PN"CR6"1;
"VSS<392>"
$PN"CP83"1;
"VSS<393>"
$PN"CP81"1;
"VSS<394>"
$PN"CP75"1;
"VSS<395>"
$PN"CP73"1;
"VSS<396>"
$PN"CP69"1;
"VSS<397>"
$PN"CP59"1;
"VSS<398>"
$PN"CP25"1;
"VSS<399>"
$PN"H59"1;
"VSS<400>"
$PN"CP1"1;
"VSS<401>"
$PN"CN78"1;
"VSS<402>"
$PN"CN68"1;
"VSS<403>"
$PN"CN62"1;
"VSS<404>"
$PN"CN60"1;
"VSS<405>"
$PN"CN32"1;
"VSS<406>"
$PN"CN26"1;
"VSS<407>"
$PN"H61"1;
"VSS<408>"
$PN"CN12"1;
"VSS<409>"
$PN"CN2"1;
"VSS<410>"
$PN"CM85"1;
"VSS<411>"
$PN"CM83"1;
"VSS<412>"
$PN"CM77"1;
"VSS<413>"
$PN"CM73"1;
"VSS<414>"
$PN"CM67"1;
"VSS<415>"
$PN"CM63"1;
"VSS<416>"
$PN"CM61"1;
"VSS<417>"
$PN"CM31"1;
"VSS<418>"
$PN"CM5"1;
"VSS<419>"
$PN"CM29"1;
"VSS<420>"
$PN"CM19"1;
"VSS<421>"
$PN"CL80"1;
"VSS<422>"
$PN"CL78"1;
"VSS<423>"
$PN"CL76"1;
"VSS<424>"
$PN"CL74"1;
"VSS<425>"
$PN"CL66"1;
"VSS<426>"
$PN"CL64"1;
"VSS<427>"
$PN"CL62"1;
"VSS<428>"
$PN"H63"1;
"VSS<429>"
$PN"P45"1;
"VSS<430>"
$PN"CL18"1;
"VSS<431>"
$PN"CL14"1;
"VSS<432>"
$PN"CL8"1;
"VSS<433>"
$PN"CK85"1;
"VSS<434>"
$PN"CK83"1;
"VSS<435>"
$PN"CK75"1;
"VSS<436>"
$PN"CK73"1;
"VSS<437>"
$PN"CK71"1;
"VSS<438>"
$PN"CK69"1;
"VSS<439>"
$PN"CK67"1;
"VSS<440>"
$PN"CK65"1;
"VSS<441>"
$PN"CK63"1;
"VSS<442>"
$PN"CK27"1;
"VSS<443>"
$PN"CK21"1;
"VSS<444>"
$PN"CK15"1;
"VSS<445>"
$PN"CK11"1;
"VSS<446>"
$PN"CJ86"1;
"VSS<447>"
$PN"CJ84"1;
"VSS<448>"
$PN"CJ82"1;
"VSS<449>"
$PN"CJ78"1;
"VSS<450>"
$PN"CJ76"1;
"VSS<451>"
$PN"CJ74"1;
"VSS<452>"
$PN"CJ62"1;
"VSS<453>"
$PN"P47"1;
%"SKX_EXT_B"
"29","(-3050,2525)","0","chpset_lib","I19";
;
CDS_SEC"29"
CDS_LOCATION"U2D1"
SEC"29"
CDS_LIB"chpset_lib"
SEC_TYPE"BGA1"
PACK_TYPE"BGA1"
MATERIAL"IC"
PART_NUMBER"TBD"
LOCATION"U2D1";
"VSS<134>"
$PN"DN72"4;
"VSS<135>"
$PN"DN68"4;
"VSS<136>"
$PN"DN38"4;
"VSS<137>"
$PN"DN32"4;
"VSS<138>"
$PN"DN26"4;
"VSS<139>"
$PN"DN22"4;
"VSS<140>"
$PN"DN12"4;
"VSS<141>"
$PN"BH17"4;
"VSS<142>"
$PN"DN2"4;
"VSS<143>"
$PN"DM83"4;
"VSS<144>"
$PN"DM77"4;
"VSS<145>"
$PN"DM73"4;
"VSS<146>"
$PN"DM65"4;
"VSS<147>"
$PN"DM39"4;
"VSS<148>"
$PN"DM37"4;
"VSS<149>"
$PN"DM33"4;
"VSS<150>"
$PN"DM31"4;
"VSS<151>"
$PN"DM27"4;
"VSS<152>"
$PN"DM25"4;
"VSS<153>"
$PN"H45"4;
"VSS<154>"
$PN"DM15"4;
"VSS<155>"
$PN"DL80"4;
"VSS<156>"
$PN"DL78"4;
"VSS<157>"
$PN"DL76"4;
"VSS<158>"
$PN"DL74"4;
"VSS<159>"
$PN"DL70"4;
"VSS<160>"
$PN"DL68"4;
"VSS<161>"
$PN"DL40"4;
"VSS<162>"
$PN"DL36"4;
"VSS<163>"
$PN"DL34"4;
"VSS<164>"
$PN"DL30"4;
"VSS<165>"
$PN"DL28"4;
"VSS<166>"
$PN"DL24"4;
"VSS<167>"
$PN"DL22"4;
"VSS<168>"
$PN"DL4"4;
"VSS<169>"
$PN"DL18"4;
"VSS<170>"
$PN"DL16"4;
"VSS<171>"
$PN"DK85"4;
"VSS<172>"
$PN"DK83"4;
"VSS<173>"
$PN"DK77"4;
"VSS<174>"
$PN"DK75"4;
"VSS<175>"
$PN"DK73"4;
"VSS<176>"
$PN"DK41"4;
"VSS<177>"
$PN"DK39"4;
"VSS<178>"
$PN"DK35"4;
"VSS<179>"
$PN"DK29"4;
"VSS<180>"
$PN"DK23"4;
"VSS<181>"
$PN"DK7"4;
"VSS<182>"
$PN"DJ84"4;
"VSS<183>"
$PN"DJ82"4;
"VSS<184>"
$PN"DJ78"4;
"VSS<185>"
$PN"DJ74"4;
"VSS<186>"
$PN"DJ68"4;
"VSS<187>"
$PN"DJ42"4;
"VSS<188>"
$PN"DJ38"4;
"VSS<189>"
$PN"DJ22"4;
"VSS<190>"
$PN"H47"4;
"VSS<191>"
$PN"DJ10"4;
"VSS<192>"
$PN"DJ2"4;
"VSS<193>"
$PN"DH83"4;
"VSS<194>"
$PN"DH81"4;
"VSS<195>"
$PN"DH79"4;
"VSS<196>"
$PN"DH73"4;
"VSS<197>"
$PN"DH71"4;
"VSS<198>"
$PN"DH67"4;
"VSS<199>"
$PN"DH41"4;
"VSS<200>"
$PN"DH37"4;
"VSS<201>"
$PN"DH35"4;
"VSS<202>"
$PN"DH33"4;
"VSS<203>"
$PN"DH31"4;
"VSS<204>"
$PN"DH29"4;
"VSS<205>"
$PN"DH27"4;
"VSS<206>"
$PN"DH25"4;
"VSS<207>"
$PN"DH23"4;
"VSS<208>"
$PN"DH15"4;
"VSS<209>"
$PN"DH13"4;
"VSS<210>"
$PN"DG82"4;
"VSS<211>"
$PN"DG80"4;
"VSS<212>"
$PN"DG78"4;
"VSS<213>"
$PN"DG76"4;
"VSS<214>"
$PN"DG68"2;
"VSS<215>"
$PN"DG66"2;
"VSS<216>"
$PN"DG24"2;
"VSS<217>"
$PN"DG16"2;
"VSS<218>"
$PN"DG14"2;
"VSS<219>"
$PN"H49"2;
"VSS<220>"
$PN"DG2"2;
"VSS<221>"
$PN"DF85"2;
"VSS<222>"
$PN"DF83"2;
"VSS<223>"
$PN"DF79"2;
"VSS<224>"
$PN"DF73"2;
"VSS<225>"
$PN"DF69"2;
"VSS<226>"
$PN"DF65"2;
"VSS<227>"
$PN"DF41"2;
"VSS<228>"
$PN"DF39"2;
"VSS<229>"
$PN"DF37"2;
"VSS<230>"
$PN"DF35"2;
"VSS<231>"
$PN"DF29"2;
"VSS<232>"
$PN"DF19"2;
"VSS<233>"
$PN"H51"2;
"VSS<234>"
$PN"DF7"2;
"VSS<235>"
$PN"DF5"2;
"VSS<236>"
$PN"DE78"2;
"VSS<237>"
$PN"DE72"2;
"VSS<238>"
$PN"DE70"2;
"VSS<239>"
$PN"DE64"2;
"VSS<240>"
$PN"DE36"2;
"VSS<241>"
$PN"DE34"2;
"VSS<242>"
$PN"DE30"2;
"VSS<243>"
$PN"DE28"2;
"VSS<244>"
$PN"DE24"2;
"VSS<245>"
$PN"DE20"2;
"VSS<246>"
$PN"DE18"2;
"VSS<247>"
$PN"DE8"2;
"VSS<248>"
$PN"DE6"2;
"VSS<249>"
$PN"DD83"2;
"VSS<250>"
$PN"DD81"2;
"VSS<251>"
$PN"DD75"2;
"VSS<252>"
$PN"DD73"2;
"VSS<253>"
$PN"DD71"2;
"VSS<254>"
$PN"DD37"2;
"VSS<255>"
$PN"DD33"2;
"VSS<256>"
$PN"DD31"2;
"VSS<257>"
$PN"DD27"2;
"VSS<258>"
$PN"DD23"2;
"VSS<259>"
$PN"DD11"2;
"VSS<260>"
$PN"DC86"2;
"VSS<261>"
$PN"DC84"2;
"VSS<262>"
$PN"DC78"2;
"VSS<263>"
$PN"DC70"2;
"VSS<264>"
$PN"DC68"2;
"VSS<265>"
$PN"DC66"2;
"VSS<266>"
$PN"DC64"2;
"VSS<267>"
$PN"DC42"2;
"VSS<268>"
$PN"DC38"2;
"VSS<269>"
$PN"DC32"2;
"VSS<270>"
$PN"DC26"2;
"VSS<271>"
$PN"DC24"2;
"VSS<272>"
$PN"DC14"2;
"VSS<273>"
$PN"DB85"2;
"VSS<274>"
$PN"DB83"2;
"VSS<275>"
$PN"DB77"2;
"VSS<276>"
$PN"DB73"2;
"VSS<277>"
$PN"DB49"2;
"VSS<278>"
$PN"DB47"2;
"VSS<279>"
$PN"DB41"2;
"VSS<280>"
$PN"DB39"2;
"VSS<281>"
$PN"DB25"2;
"VSS<282>"
$PN"DB23"2;
"VSS<283>"
$PN"DB17"2;
"VSS<284>"
$PN"DB13"2;
"VSS<285>"
$PN"DB3"2;
"VSS<286>"
$PN"DA80"2;
"VSS<287>"
$PN"DA78"2;
"VSS<288>"
$PN"DA76"2;
"VSS<289>"
$PN"DA74"2;
"VSS<290>"
$PN"DA70"2;
"VSS<291>"
$PN"DA64"2;
"VSS<292>"
$PN"DA50"2;
"VSS<293>"
$PN"DA48"2;
%"SKX_EXT_B"
"30","(-1225,2550)","0","chpset_lib","I20";
;
CDS_SEC"30"
CDS_LOCATION"U2D1"
SEC"30"
CDS_LIB"chpset_lib"
SEC_TYPE"BGA1"
PACK_TYPE"BGA1"
MATERIAL"IC"
PART_NUMBER"TBD"
LOCATION"U2D1";
"VSS<0>"
$PN"EF79"7;
"VSS<1>"
$PN"EF75"7;
"VSS<2>"
$PN"EF71"7;
"VSS<3>"
$PN"EE78"7;
"VSS<4>"
$PN"EE76"7;
"VSS<5>"
$PN"EE70"7;
"VSS<6>"
$PN"EE36"7;
"VSS<7>"
$PN"EE34"7;
"VSS<8>"
$PN"EE30"7;
"VSS<9>"
$PN"EE28"7;
"VSS<10>"
$PN"EE24"7;
"VSS<11>"
$PN"ED77"7;
"VSS<12>"
$PN"ED35"7;
"VSS<13>"
$PN"ED29"7;
"VSS<14>"
$PN"ED23"7;
"VSS<15>"
$PN"ED15"7;
"VSS<16>"
$PN"ED11"7;
"VSS<17>"
$PN"EC76"7;
"VSS<18>"
$PN"EC74"7;
"VSS<19>"
$PN"EC72"7;
"VSS<20>"
$PN"EC70"7;
"VSS<21>"
$PN"EC10"7;
"VSS<22>"
$PN"EB69"7;
"VSS<23>"
$PN"EB65"7;
"VSS<24>"
$PN"EB41"7;
"VSS<25>"
$PN"EB39"7;
"VSS<26>"
$PN"EB37"7;
"VSS<27>"
$PN"EB35"7;
"VSS<28>"
$PN"EB33"7;
"VSS<29>"
$PN"EB31"7;
"VSS<30>"
$PN"EB29"7;
"VSS<31>"
$PN"EB27"7;
"VSS<32>"
$PN"EB25"7;
"VSS<33>"
$PN"EB23"7;
"VSS<34>"
$PN"BR18"7;
"VSS<35>"
$PN"EB13"7;
"VSS<36>"
$PN"EA82"7;
"VSS<37>"
$PN"EA80"7;
"VSS<38>"
$PN"EA78"7;
"VSS<39>"
$PN"EA76"7;
"VSS<40>"
$PN"EA70"7;
"VSS<41>"
$PN"EA64"7;
"VSS<42>"
$PN"EA42"7;
"VSS<43>"
$PN"EA22"7;
"VSS<44>"
$PN"EA20"7;
"VSS<45>"
$PN"EA16"7;
"VSS<46>"
$PN"J16"7;
"VSS<47>"
$PN"EA6"7;
"VSS<48>"
$PN"DY75"7;
"VSS<49>"
$PN"DY71"7;
"VSS<50>"
$PN"DY41"7;
"VSS<51>"
$PN"DY35"7;
"VSS<52>"
$PN"DY29"7;
"VSS<53>"
$PN"DY23"7;
"VSS<54>"
$PN"DY19"3;
"VSS<55>"
$PN"DY5"3;
"VSS<56>"
$PN"DW84"3;
"VSS<57>"
$PN"DW82"3;
"VSS<58>"
$PN"DW8"3;
"VSS<59>"
$PN"DW76"3;
"VSS<60>"
$PN"DW74"3;
"VSS<61>"
$PN"DW72"3;
"VSS<62>"
$PN"DW70"3;
"VSS<63>"
$PN"DW68"3;
"VSS<64>"
$PN"DW66"3;
"VSS<65>"
$PN"DW64"3;
"VSS<66>"
$PN"DW40"3;
"VSS<67>"
$PN"DW36"3;
"VSS<68>"
$PN"DW34"3;
"VSS<69>"
$PN"DW30"3;
"VSS<70>"
$PN"DW28"3;
"VSS<71>"
$PN"DW24"3;
"VSS<72>"
$PN"DW20"3;
"VSS<73>"
$PN"DW12"3;
"VSS<74>"
$PN"DV81"3;
"VSS<75>"
$PN"DV77"3;
"VSS<76>"
$PN"DV73"3;
"VSS<77>"
$PN"DV39"3;
"VSS<78>"
$PN"DV37"3;
"VSS<79>"
$PN"DV33"3;
"VSS<80>"
$PN"DV31"3;
"VSS<81>"
$PN"DV27"3;
"VSS<82>"
$PN"DV25"3;
"VSS<83>"
$PN"DV21"3;
"VSS<84>"
$PN"DU84"3;
"VSS<85>"
$PN"DU82"3;
"VSS<86>"
$PN"DU80"3;
"VSS<87>"
$PN"DU78"3;
"VSS<88>"
$PN"DU72"3;
"VSS<89>"
$PN"DU70"3;
"VSS<90>"
$PN"DU38"3;
"VSS<91>"
$PN"DU32"3;
"VSS<92>"
$PN"DU26"3;
"VSS<93>"
$PN"DU22"3;
"VSS<94>"
$PN"CN14"3;
"VSS<95>"
$PN"DU14"3;
"VSS<96>"
$PN"DU10"3;
"VSS<97>"
$PN"DT85"3;
"VSS<98>"
$PN"DT83"3;
"VSS<99>"
$PN"DT79"3;
"VSS<100>"
$PN"DT69"3;
"VSS<101>"
$PN"DT65"3;
"VSS<102>"
$PN"DH21"3;
"VSS<103>"
$PN"DT17"3;
"VSS<104>"
$PN"DT3"3;
"VSS<105>"
$PN"DR78"3;
"VSS<106>"
$PN"DR76"3;
"VSS<107>"
$PN"DR74"3;
"VSS<108>"
$PN"DR72"3;
"VSS<109>"
$PN"DR70"3;
"VSS<110>"
$PN"DR68"3;
"VSS<111>"
$PN"DR66"3;
"VSS<112>"
$PN"DR42"3;
"VSS<113>"
$PN"DR40"3;
"VSS<114>"
$PN"DR38"3;
"VSS<115>"
$PN"DR36"3;
"VSS<116>"
$PN"DR34"3;
"VSS<117>"
$PN"DR32"3;
"VSS<118>"
$PN"DR30"3;
"VSS<119>"
$PN"DR28"3;
"VSS<120>"
$PN"DR26"3;
"VSS<121>"
$PN"DR24"3;
"VSS<122>"
$PN"DR22"3;
"VSS<123>"
$PN"DR20"3;
"VSS<124>"
$PN"CL22"3;
"VSS<125>"
$PN"CA20"3;
"VSS<126>"
$PN"DR6"3;
"VSS<127>"
$PN"BR26"3;
"VSS<128>"
$PN"DP83"3;
"VSS<129>"
$PN"DP81"3;
"VSS<130>"
$PN"DP71"3;
"VSS<131>"
$PN"DP69"3;
"VSS<132>"
$PN"DP67"3;
"VSS<133>"
$PN"DN78"3;
%"GND"
"1","(-7475,400)","0","mstr_symbols","I9";
;
HDL_POWER"GND"
BODY_TYPE"PLUMBING"
SIZE"1B"
CDS_LIB"mstr_symbols"
VOLTAGE"0.0V";
"A\NAC"8;
END.
